(kicad_pcb
	(version 20260206)
	(generator "pcbnew")
	(generator_version "10.0")
	(general
		(thickness 1.6)
		(legacy_teardrops no)
	)
	(paper "A4")
	(title_block
		(title "03242023_DA0F0TMBIJ0_F0T_Motherboard_J_brd_V01_OCP.brd")
		(comment 1 "Grand Teton / footprints 4355-4360 of 6105")
	)
	(layers
		(0 "F.Cu" signal "TOP")
		(4 "In1.Cu" signal "GND")
		(6 "In2.Cu" signal "IN1")
		(8 "In3.Cu" signal "GND1")
		(10 "In4.Cu" signal "IN2")
		(12 "In5.Cu" signal "GND2")
		(14 "In6.Cu" signal "IN3")
		(16 "In7.Cu" signal "GND3")
		(18 "In8.Cu" signal "VCC")
		(20 "In9.Cu" signal "VCC1")
		(22 "In10.Cu" signal "GND4")
		(24 "In11.Cu" signal "IN4")
		(26 "In12.Cu" signal "GND5")
		(28 "In13.Cu" signal "IN5")
		(30 "In14.Cu" signal "GND6")
		(32 "In15.Cu" signal "IN6")
		(34 "In16.Cu" signal "GND7")
		(2 "B.Cu" signal "BOTTOM")
		(9 "F.Adhes" user "F.Adhesive")
		(11 "B.Adhes" user "B.Adhesive")
		(13 "F.Paste" user "Package Geometry/Pastemask Top")
		(15 "B.Paste" user "Package Geometry/Pastemask Bottom")
		(5 "F.SilkS" user "Ref Des/Silkscreen Top")
		(7 "B.SilkS" user "Ref Des/Silkscreen Bottom")
		(1 "F.Mask" user "Board Geometry/Soldermask Top")
		(3 "B.Mask" user "Board Geometry/Soldermask Bottom")
		(17 "Dwgs.User" user "User.Drawings")
		(19 "Cmts.User" user "User.Comments")
		(21 "Eco1.User" user "User.Eco1")
		(23 "Eco2.User" user "User.Eco2")
		(25 "Edge.Cuts" user "Board Geometry/Outline")
		(27 "Margin" user)
		(31 "F.CrtYd" user "Package Geometry/Place Bound Top")
		(29 "B.CrtYd" user "Package Geometry/Place Bound Bottom")
		(35 "F.Fab" user "Ref Des/Assembly Top")
		(33 "B.Fab" user "Ref Des/Assembly Bottom")
	)
	(footprint ""
		(layer "B.Cu")
		(at 173.04893 -103.723948)
		(property "Reference" "C1940"
			(at 0 0 0)
			(layer "B.SilkS")
			(hide yes)
			(effects
				(font
					(size 1.27 1.27)
				)
				(justify mirror)
			)
		)
		(property "Value" ""
			(at 0 0 0)
			(layer "B.Fab")
			(effects
				(font
					(size 1.27 1.27)
				)
				(justify mirror)
			)
		)
		(duplicate_pad_numbers_are_jumpers no)
		(fp_line
			(start -0.7874 -0.4064)
			(end -0.7874 0.4064)
			(stroke
				(width 0.1524)
				(type default)
			)
			(layer "B.SilkS")
		)
		(fp_line
			(start -0.7874 0.4064)
			(end 0.7874 0.4064)
			(stroke
				(width 0.1524)
				(type default)
			)
			(layer "B.SilkS")
		)
		(fp_line
			(start 0.7874 -0.4064)
			(end -0.7874 -0.4064)
			(stroke
				(width 0.1524)
				(type default)
			)
			(layer "B.SilkS")
		)
		(fp_line
			(start 0.7874 0.4064)
			(end 0.7874 -0.4064)
			(stroke
				(width 0.1524)
				(type default)
			)
			(layer "B.SilkS")
		)
		(fp_line
			(start -0.67945 -0.3048)
			(end -0.67945 0.3048)
			(stroke
				(width 0.1)
				(type default)
			)
			(layer "B.Fab")
		)
		(fp_line
			(start -0.67945 0.3048)
			(end -0.120396 0.3048)
			(stroke
				(width 0.1)
				(type default)
			)
			(layer "B.Fab")
		)
		(fp_line
			(start -0.12065 -0.3048)
			(end -0.67945 -0.3048)
			(stroke
				(width 0.1)
				(type default)
			)
			(layer "B.Fab")
		)
		(fp_line
			(start -0.12065 -0.2794)
			(end -0.12065 -0.3048)
			(stroke
				(width 0.1)
				(type default)
			)
			(layer "B.Fab")
		)
		(fp_line
			(start -0.120396 0.2794)
			(end 0.12065 0.2794)
			(stroke
				(width 0.1)
				(type default)
			)
			(layer "B.Fab")
		)
		(fp_line
			(start -0.120396 0.3048)
			(end -0.120396 0.2794)
			(stroke
				(width 0.1)
				(type default)
			)
			(layer "B.Fab")
		)
		(fp_line
			(start 0.12065 -0.305054)
			(end 0.12065 -0.2794)
			(stroke
				(width 0.1)
				(type default)
			)
			(layer "B.Fab")
		)
		(fp_line
			(start 0.12065 -0.2794)
			(end -0.12065 -0.2794)
			(stroke
				(width 0.1)
				(type default)
			)
			(layer "B.Fab")
		)
		(fp_line
			(start 0.12065 0.2794)
			(end 0.12065 0.3048)
			(stroke
				(width 0.1)
				(type default)
			)
			(layer "B.Fab")
		)
		(fp_line
			(start 0.12065 0.3048)
			(end 0.67945 0.3048)
			(stroke
				(width 0.1)
				(type default)
			)
			(layer "B.Fab")
		)
		(fp_line
			(start 0.67945 -0.305054)
			(end 0.12065 -0.305054)
			(stroke
				(width 0.1)
				(type default)
			)
			(layer "B.Fab")
		)
		(fp_line
			(start 0.67945 0.3048)
			(end 0.67945 -0.305054)
			(stroke
				(width 0.1)
				(type default)
			)
			(layer "B.Fab")
		)
		(pad "1" smd circle
			(at 0.40005 0 180)
			(size 0 0)
			(layers "B.Cu" "B.Mask" "B.Paste")
			(net "P3V3_AUX_FPGA_VCCIO5")
		)
		(pad "2" smd circle
			(at -0.40005 0 180)
			(size 0 0)
			(layers "B.Cu" "B.Mask" "B.Paste")
			(net "GND")
		)
	)
	(footprint ""
		(layer "B.Cu")
		(at 445.866012 -58.300112 -90)
		(property "Reference" "PC1869"
			(at 0 0 90)
			(layer "B.SilkS")
			(hide yes)
			(effects
				(font
					(size 1.27 1.27)
				)
				(justify mirror)
			)
		)
		(property "Value" ""
			(at 0 0 90)
			(layer "B.Fab")
			(effects
				(font
					(size 1.27 1.27)
				)
				(justify mirror)
			)
		)
		(duplicate_pad_numbers_are_jumpers no)
		(fp_line
			(start -0.7874 0.4064)
			(end 0.7874 0.4064)
			(stroke
				(width 0.1524)
				(type default)
			)
			(layer "B.SilkS")
		)
		(fp_line
			(start 0.7874 0.4064)
			(end 0.7874 -0.4064)
			(stroke
				(width 0.1524)
				(type default)
			)
			(layer "B.SilkS")
		)
		(fp_line
			(start -0.7874 -0.4064)
			(end -0.7874 0.4064)
			(stroke
				(width 0.1524)
				(type default)
			)
			(layer "B.SilkS")
		)
		(fp_line
			(start 0.7874 -0.4064)
			(end -0.7874 -0.4064)
			(stroke
				(width 0.1524)
				(type default)
			)
			(layer "B.SilkS")
		)
		(fp_line
			(start -0.67945 0.3048)
			(end -0.120396 0.3048)
			(stroke
				(width 0.1)
				(type default)
			)
			(layer "B.Fab")
		)
		(fp_line
			(start -0.120396 0.3048)
			(end -0.120396 0.2794)
			(stroke
				(width 0.1)
				(type default)
			)
			(layer "B.Fab")
		)
		(fp_line
			(start 0.12065 0.3048)
			(end 0.67945 0.3048)
			(stroke
				(width 0.1)
				(type default)
			)
			(layer "B.Fab")
		)
		(fp_line
			(start 0.67945 0.3048)
			(end 0.67945 -0.305054)
			(stroke
				(width 0.1)
				(type default)
			)
			(layer "B.Fab")
		)
		(fp_line
			(start -0.120396 0.2794)
			(end 0.12065 0.2794)
			(stroke
				(width 0.1)
				(type default)
			)
			(layer "B.Fab")
		)
		(fp_line
			(start 0.12065 0.2794)
			(end 0.12065 0.3048)
			(stroke
				(width 0.1)
				(type default)
			)
			(layer "B.Fab")
		)
		(fp_line
			(start -0.12065 -0.2794)
			(end -0.12065 -0.3048)
			(stroke
				(width 0.1)
				(type default)
			)
			(layer "B.Fab")
		)
		(fp_line
			(start 0.12065 -0.2794)
			(end -0.12065 -0.2794)
			(stroke
				(width 0.1)
				(type default)
			)
			(layer "B.Fab")
		)
		(fp_line
			(start -0.67945 -0.3048)
			(end -0.67945 0.3048)
			(stroke
				(width 0.1)
				(type default)
			)
			(layer "B.Fab")
		)
		(fp_line
			(start -0.12065 -0.3048)
			(end -0.67945 -0.3048)
			(stroke
				(width 0.1)
				(type default)
			)
			(layer "B.Fab")
		)
		(fp_line
			(start 0.12065 -0.305054)
			(end 0.12065 -0.2794)
			(stroke
				(width 0.1)
				(type default)
			)
			(layer "B.Fab")
		)
		(fp_line
			(start 0.67945 -0.305054)
			(end 0.12065 -0.305054)
			(stroke
				(width 0.1)
				(type default)
			)
			(layer "B.Fab")
		)
		(pad "1" smd circle
			(at 0.40005 0 90)
			(size 0 0)
			(layers "B.Cu" "B.Mask" "B.Paste")
			(net "P3V3_AUX")
		)
		(pad "2" smd circle
			(at -0.40005 0 90)
			(size 0 0)
			(layers "B.Cu" "B.Mask" "B.Paste")
			(net "GND")
		)
	)
	(footprint ""
		(layer "B.Cu")
		(at 108.42371 -417.069524 180)
		(property "Reference" "R4493"
			(at 0 0 0)
			(layer "B.SilkS")
			(hide yes)
			(effects
				(font
					(size 1.27 1.27)
				)
				(justify mirror)
			)
		)
		(property "Value" ""
			(at 0 0 0)
			(layer "B.Fab")
			(effects
				(font
					(size 1.27 1.27)
				)
				(justify mirror)
			)
		)
		(duplicate_pad_numbers_are_jumpers no)
		(fp_line
			(start 1.2954 0.5842)
			(end 1.2954 -0.5842)
			(stroke
				(width 0.1524)
				(type default)
			)
			(layer "B.SilkS")
		)
		(fp_line
			(start 1.2954 -0.5842)
			(end -1.2954 -0.5842)
			(stroke
				(width 0.1524)
				(type default)
			)
			(layer "B.SilkS")
		)
		(fp_line
			(start -1.2954 0.5842)
			(end 1.2954 0.5842)
			(stroke
				(width 0.1524)
				(type default)
			)
			(layer "B.SilkS")
		)
		(fp_line
			(start -1.2954 -0.5842)
			(end -1.2954 0.5842)
			(stroke
				(width 0.1524)
				(type default)
			)
			(layer "B.SilkS")
		)
		(fp_line
			(start 1.1938 0.4064)
			(end 1.1938 -0.406654)
			(stroke
				(width 0.1)
				(type default)
			)
			(layer "B.Fab")
		)
		(fp_line
			(start 1.1938 -0.406654)
			(end 0.8636 -0.406654)
			(stroke
				(width 0.1)
				(type default)
			)
			(layer "B.Fab")
		)
		(fp_line
			(start 0.8636 0.4572)
			(end 0.8636 0.4318)
			(stroke
				(width 0.1)
				(type default)
			)
			(layer "B.Fab")
		)
		(fp_line
			(start 0.8636 0.4318)
			(end 0.8636 0.4064)
			(stroke
				(width 0.1)
				(type default)
			)
			(layer "B.Fab")
		)
		(fp_line
			(start 0.8636 0.4064)
			(end 1.1938 0.4064)
			(stroke
				(width 0.1)
				(type default)
			)
			(layer "B.Fab")
		)
		(fp_line
			(start 0.8636 -0.406654)
			(end 0.8636 -0.4572)
			(stroke
				(width 0.1)
				(type default)
			)
			(layer "B.Fab")
		)
		(fp_line
			(start 0.8636 -0.4572)
			(end -0.8636 -0.4572)
			(stroke
				(width 0.1)
				(type default)
			)
			(layer "B.Fab")
		)
		(fp_line
			(start -0.8636 0.4572)
			(end 0.8636 0.4572)
			(stroke
				(width 0.1)
				(type default)
			)
			(layer "B.Fab")
		)
		(fp_line
			(start -0.8636 0.4064)
			(end -0.8636 0.4572)
			(stroke
				(width 0.1)
				(type default)
			)
			(layer "B.Fab")
		)
		(fp_line
			(start -0.8636 -0.406654)
			(end -1.1938 -0.406654)
			(stroke
				(width 0.1)
				(type default)
			)
			(layer "B.Fab")
		)
		(fp_line
			(start -0.8636 -0.4572)
			(end -0.8636 -0.406654)
			(stroke
				(width 0.1)
				(type default)
			)
			(layer "B.Fab")
		)
		(fp_line
			(start -1.1938 0.4064)
			(end -0.8636 0.4064)
			(stroke
				(width 0.1)
				(type default)
			)
			(layer "B.Fab")
		)
		(fp_line
			(start -1.1938 -0.406654)
			(end -1.1938 0.4064)
			(stroke
				(width 0.1)
				(type default)
			)
			(layer "B.Fab")
		)
		(pad "1" smd rect
			(at 0.7366 0 90)
			(size 0.7112 0.8128)
			(layers "B.Cu" "B.Mask" "B.Paste")
			(net "P3V3_9ZXL045")
		)
		(pad "2" smd rect
			(at -0.7366 0 90)
			(size 0.7112 0.8128)
			(layers "B.Cu" "B.Mask" "B.Paste")
			(net "P3V3_9ZXL045_VDDA")
		)
	)
	(footprint ""
		(layer "B.Cu")
		(at 53.912516 -154.081226)
		(property "Reference" "PR254"
			(at 0 0 0)
			(layer "B.SilkS")
			(hide yes)
			(effects
				(font
					(size 1.27 1.27)
				)
				(justify mirror)
			)
		)
		(property "Value" ""
			(at 0 0 0)
			(layer "B.Fab")
			(effects
				(font
					(size 1.27 1.27)
				)
				(justify mirror)
			)
		)
		(duplicate_pad_numbers_are_jumpers no)
		(fp_line
			(start -0.7874 -0.4064)
			(end -0.7874 0.4064)
			(stroke
				(width 0.1524)
				(type default)
			)
			(layer "B.SilkS")
		)
		(fp_line
			(start -0.7874 0.4064)
			(end 0.7874 0.4064)
			(stroke
				(width 0.1524)
				(type default)
			)
			(layer "B.SilkS")
		)
		(fp_line
			(start 0.7874 -0.4064)
			(end -0.7874 -0.4064)
			(stroke
				(width 0.1524)
				(type default)
			)
			(layer "B.SilkS")
		)
		(fp_line
			(start 0.7874 0.4064)
			(end 0.7874 -0.4064)
			(stroke
				(width 0.1524)
				(type default)
			)
			(layer "B.SilkS")
		)
		(fp_line
			(start -0.67945 -0.3048)
			(end -0.67945 0.3048)
			(stroke
				(width 0.1)
				(type default)
			)
			(layer "B.Fab")
		)
		(fp_line
			(start -0.67945 0.3048)
			(end -0.120396 0.3048)
			(stroke
				(width 0.1)
				(type default)
			)
			(layer "B.Fab")
		)
		(fp_line
			(start -0.12065 -0.3048)
			(end -0.67945 -0.3048)
			(stroke
				(width 0.1)
				(type default)
			)
			(layer "B.Fab")
		)
		(fp_line
			(start -0.12065 -0.2794)
			(end -0.12065 -0.3048)
			(stroke
				(width 0.1)
				(type default)
			)
			(layer "B.Fab")
		)
		(fp_line
			(start -0.120396 0.2794)
			(end 0.12065 0.2794)
			(stroke
				(width 0.1)
				(type default)
			)
			(layer "B.Fab")
		)
		(fp_line
			(start -0.120396 0.3048)
			(end -0.120396 0.2794)
			(stroke
				(width 0.1)
				(type default)
			)
			(layer "B.Fab")
		)
		(fp_line
			(start 0.12065 -0.305054)
			(end 0.12065 -0.2794)
			(stroke
				(width 0.1)
				(type default)
			)
			(layer "B.Fab")
		)
		(fp_line
			(start 0.12065 -0.2794)
			(end -0.12065 -0.2794)
			(stroke
				(width 0.1)
				(type default)
			)
			(layer "B.Fab")
		)
		(fp_line
			(start 0.12065 0.2794)
			(end 0.12065 0.3048)
			(stroke
				(width 0.1)
				(type default)
			)
			(layer "B.Fab")
		)
		(fp_line
			(start 0.12065 0.3048)
			(end 0.67945 0.3048)
			(stroke
				(width 0.1)
				(type default)
			)
			(layer "B.Fab")
		)
		(fp_line
			(start 0.67945 -0.305054)
			(end 0.12065 -0.305054)
			(stroke
				(width 0.1)
				(type default)
			)
			(layer "B.Fab")
		)
		(fp_line
			(start 0.67945 0.3048)
			(end 0.67945 -0.305054)
			(stroke
				(width 0.1)
				(type default)
			)
			(layer "B.Fab")
		)
		(pad "1" smd circle
			(at 0.40005 0 180)
			(size 0 0)
			(layers "B.Cu" "B.Mask" "B.Paste")
			(net "PVCCFA_EHV_CPU1_PVCC")
		)
		(pad "2" smd circle
			(at -0.40005 0 180)
			(size 0 0)
			(layers "B.Cu" "B.Mask" "B.Paste")
			(net "PVCCINFAON_CPU1_VDD1")
		)
	)
	(footprint ""
		(layer "B.Cu")
		(at 36.968938 -127.41656)
		(property "Reference" "R2558"
			(at 0 0 0)
			(layer "B.SilkS")
			(hide yes)
			(effects
				(font
					(size 1.27 1.27)
				)
				(justify mirror)
			)
		)
		(property "Value" ""
			(at 0 0 0)
			(layer "B.Fab")
			(effects
				(font
					(size 1.27 1.27)
				)
				(justify mirror)
			)
		)
		(duplicate_pad_numbers_are_jumpers no)
		(fp_line
			(start -0.7874 -0.4064)
			(end -0.7874 0.4064)
			(stroke
				(width 0.1524)
				(type default)
			)
			(layer "B.SilkS")
		)
		(fp_line
			(start -0.7874 0.4064)
			(end 0.7874 0.4064)
			(stroke
				(width 0.1524)
				(type default)
			)
			(layer "B.SilkS")
		)
		(fp_line
			(start 0.7874 -0.4064)
			(end -0.7874 -0.4064)
			(stroke
				(width 0.1524)
				(type default)
			)
			(layer "B.SilkS")
		)
		(fp_line
			(start 0.7874 0.4064)
			(end 0.7874 -0.4064)
			(stroke
				(width 0.1524)
				(type default)
			)
			(layer "B.SilkS")
		)
		(fp_line
			(start -0.67945 -0.3048)
			(end -0.67945 0.3048)
			(stroke
				(width 0.1)
				(type default)
			)
			(layer "B.Fab")
		)
		(fp_line
			(start -0.67945 0.3048)
			(end -0.120396 0.3048)
			(stroke
				(width 0.1)
				(type default)
			)
			(layer "B.Fab")
		)
		(fp_line
			(start -0.12065 -0.3048)
			(end -0.67945 -0.3048)
			(stroke
				(width 0.1)
				(type default)
			)
			(layer "B.Fab")
		)
		(fp_line
			(start -0.12065 -0.2794)
			(end -0.12065 -0.3048)
			(stroke
				(width 0.1)
				(type default)
			)
			(layer "B.Fab")
		)
		(fp_line
			(start -0.120396 0.2794)
			(end 0.12065 0.2794)
			(stroke
				(width 0.1)
				(type default)
			)
			(layer "B.Fab")
		)
		(fp_line
			(start -0.120396 0.3048)
			(end -0.120396 0.2794)
			(stroke
				(width 0.1)
				(type default)
			)
			(layer "B.Fab")
		)
		(fp_line
			(start 0.12065 -0.305054)
			(end 0.12065 -0.2794)
			(stroke
				(width 0.1)
				(type default)
			)
			(layer "B.Fab")
		)
		(fp_line
			(start 0.12065 -0.2794)
			(end -0.12065 -0.2794)
			(stroke
				(width 0.1)
				(type default)
			)
			(layer "B.Fab")
		)
		(fp_line
			(start 0.12065 0.2794)
			(end 0.12065 0.3048)
			(stroke
				(width 0.1)
				(type default)
			)
			(layer "B.Fab")
		)
		(fp_line
			(start 0.12065 0.3048)
			(end 0.67945 0.3048)
			(stroke
				(width 0.1)
				(type default)
			)
			(layer "B.Fab")
		)
		(fp_line
			(start 0.67945 -0.305054)
			(end 0.12065 -0.305054)
			(stroke
				(width 0.1)
				(type default)
			)
			(layer "B.Fab")
		)
		(fp_line
			(start 0.67945 0.3048)
			(end 0.67945 -0.305054)
			(stroke
				(width 0.1)
				(type default)
			)
			(layer "B.Fab")
		)
		(pad "1" smd circle
			(at 0.40005 0 180)
			(size 0 0)
			(layers "B.Cu" "B.Mask" "B.Paste")
			(net "FM_PVCCINFAON_CPU1_EN")
		)
		(pad "2" smd circle
			(at -0.40005 0 180)
			(size 0 0)
			(layers "B.Cu" "B.Mask" "B.Paste")
			(net "PVCCINFAON_CPU1_EN_R")
		)
	)
	(footprint ""
		(layer "B.Cu")
		(at 339.12048 -53.471826 90)
		(property "Reference" "R1463"
			(at 0 0 90)
			(layer "B.SilkS")
			(hide yes)
			(effects
				(font
					(size 1.27 1.27)
				)
				(justify mirror)
			)
		)
		(property "Value" ""
			(at 0 0 90)
			(layer "B.Fab")
			(effects
				(font
					(size 1.27 1.27)
				)
				(justify mirror)
			)
		)
		(duplicate_pad_numbers_are_jumpers no)
		(fp_line
			(start 0.7874 -0.4064)
			(end -0.7874 -0.4064)
			(stroke
				(width 0.1524)
				(type default)
			)
			(layer "B.SilkS")
		)
		(fp_line
			(start -0.7874 -0.4064)
			(end -0.7874 0.4064)
			(stroke
				(width 0.1524)
				(type default)
			)
			(layer "B.SilkS")
		)
		(fp_line
			(start 0.7874 0.4064)
			(end 0.7874 -0.4064)
			(stroke
				(width 0.1524)
				(type default)
			)
			(layer "B.SilkS")
		)
		(fp_line
			(start -0.7874 0.4064)
			(end 0.7874 0.4064)
			(stroke
				(width 0.1524)
				(type default)
			)
			(layer "B.SilkS")
		)
		(fp_line
			(start 0.67945 -0.305054)
			(end 0.12065 -0.305054)
			(stroke
				(width 0.1)
				(type default)
			)
			(layer "B.Fab")
		)
		(fp_line
			(start 0.12065 -0.305054)
			(end 0.12065 -0.2794)
			(stroke
				(width 0.1)
				(type default)
			)
			(layer "B.Fab")
		)
		(fp_line
			(start -0.12065 -0.3048)
			(end -0.67945 -0.3048)
			(stroke
				(width 0.1)
				(type default)
			)
			(layer "B.Fab")
		)
		(fp_line
			(start -0.67945 -0.3048)
			(end -0.67945 0.3048)
			(stroke
				(width 0.1)
				(type default)
			)
			(layer "B.Fab")
		)
		(fp_line
			(start 0.12065 -0.2794)
			(end -0.12065 -0.2794)
			(stroke
				(width 0.1)
				(type default)
			)
			(layer "B.Fab")
		)
		(fp_line
			(start -0.12065 -0.2794)
			(end -0.12065 -0.3048)
			(stroke
				(width 0.1)
				(type default)
			)
			(layer "B.Fab")
		)
		(fp_line
			(start 0.12065 0.2794)
			(end 0.12065 0.3048)
			(stroke
				(width 0.1)
				(type default)
			)
			(layer "B.Fab")
		)
		(fp_line
			(start -0.120396 0.2794)
			(end 0.12065 0.2794)
			(stroke
				(width 0.1)
				(type default)
			)
			(layer "B.Fab")
		)
		(fp_line
			(start 0.67945 0.3048)
			(end 0.67945 -0.305054)
			(stroke
				(width 0.1)
				(type default)
			)
			(layer "B.Fab")
		)
		(fp_line
			(start 0.12065 0.3048)
			(end 0.67945 0.3048)
			(stroke
				(width 0.1)
				(type default)
			)
			(layer "B.Fab")
		)
		(fp_line
			(start -0.120396 0.3048)
			(end -0.120396 0.2794)
			(stroke
				(width 0.1)
				(type default)
			)
			(layer "B.Fab")
		)
		(fp_line
			(start -0.67945 0.3048)
			(end -0.120396 0.3048)
			(stroke
				(width 0.1)
				(type default)
			)
			(layer "B.Fab")
		)
		(pad "1" smd circle
			(at 0.40005 0 270)
			(size 0 0)
			(layers "B.Cu" "B.Mask" "B.Paste")
			(net "P1V05_PCH_AUX")
		)
		(pad "2" smd circle
			(at -0.40005 0 270)
			(size 0 0)
			(layers "B.Cu" "B.Mask" "B.Paste")
			(net "P1V05_PCH_PLL_AUX")
		)
	)
)
